# S9S_MB_2U (Grand Teton) — schematic netlist excerpt (pin names and nets, part order shuffled) for the footprints in the layout excerpt that follows; sources: Cadence DE-HDL packaged netlist, KiCad conversion of 03242023_DA0F0TMBIJ0_F0T_Motherboard_J_brd_V01_OCP.brd

J105  CONN112_10137002101LF  CONN112_10137002-101LF IO  pkg HSD_F112D8_P2W1-2_RDH  page 136
  A1  = GPU_3V3IO_RSVD4
  A2  = GND
  A3  = GPU_WP_HW_CTRL_ISO
  A4  = GND
  A5  = GPU_3V3IO_RSVD3
  A6  = GND
  A7  = GPU_3V3IO_RSVD1
  A8  = GND
  B1  = GND
  B2  = P5E_CPU0_PE3_RX_DP<6>
  B3  = GND
  B4  = P5E_CPU0_PE3_RX_DP<4>
  B5  = GND
  B6  = P5E_CPU0_PE3_RX_DN<2>
  B7  = GND
  B8  = P5E_CPU0_PE3_RX_DP<0>
  C1  = P5E_CPU0_PE3_RX_DP<7>
  C2  = P5E_CPU0_PE3_RX_DN<6>
  C3  = P5E_CPU0_PE3_RX_DP<5>
  C4  = P5E_CPU0_PE3_RX_DN<4>
  C5  = P5E_CPU0_PE3_RX_DN<3>
  C6  = P5E_CPU0_PE3_RX_DP<2>
  C7  = P5E_CPU0_PE3_RX_DN<1>
  C8  = P5E_CPU0_PE3_RX_DN<0>
  D1  = P5E_CPU0_PE3_RX_DN<7>
  D2  = GND
  D3  = P5E_CPU0_PE3_RX_DN<5>
  D4  = GND
  D5  = P5E_CPU0_PE3_RX_DP<3>
  D6  = GND
  D7  = P5E_CPU0_PE3_RX_DP<1>
  D8  = GND
  E1  = GND
  E2  = P5E_CPU0_PE2_RX_DP<6>
  E3  = GND
  E4  = P5E_CPU0_PE2_RX_DP<4>
  E5  = GND
  E6  = P5E_CPU0_PE2_RX_DP<2>
  E7  = GND
  E8  = P5E_CPU0_PE2_RX_DP<0>
  F1  = P5E_CPU0_PE2_RX_DP<7>
  F2  = P5E_CPU0_PE2_RX_DN<6>
  F3  = P5E_CPU0_PE2_RX_DP<5>
  F4  = P5E_CPU0_PE2_RX_DN<4>
  F5  = P5E_CPU0_PE2_RX_DP<3>
  F6  = P5E_CPU0_PE2_RX_DN<2>
  F7  = P5E_CPU0_PE2_RX_DP<1>
  F8  = P5E_CPU0_PE2_RX_DN<0>
  G1  = P5E_CPU0_PE2_RX_DN<7>
  G2  = GND
  G3  = P5E_CPU0_PE2_RX_DN<5>
  G4  = GND
  G5  = P5E_CPU0_PE2_RX_DN<3>
  G6  = GND
  G7  = P5E_CPU0_PE2_RX_DN<1>
  G8  = GND
  H1  = GND
  H2  = P5E_CPU0_PE3_TX_C_DN<6>
  H3  = GND
  H4  = P5E_CPU0_PE3_TX_C_DN<4>
  H5  = GND
  H6  = P5E_CPU0_PE3_TX_C_DN<2>
  H7  = GND
  H8  = P5E_CPU0_PE3_TX_C_DP<0>
  I1  = P5E_CPU0_PE3_TX_C_DN<7>
  I2  = P5E_CPU0_PE3_TX_C_DP<6>
  I3  = P5E_CPU0_PE3_TX_C_DN<5>
  I4  = P5E_CPU0_PE3_TX_C_DP<4>
  I5  = P5E_CPU0_PE3_TX_C_DN<3>
  I6  = P5E_CPU0_PE3_TX_C_DP<2>
  I7  = P5E_CPU0_PE3_TX_C_DN<1>
  I8  = P5E_CPU0_PE3_TX_C_DN<0>
  J1  = P5E_CPU0_PE3_TX_C_DP<7>
  J2  = GND
  J3  = P5E_CPU0_PE3_TX_C_DP<5>
  J4  = GND
  J5  = P5E_CPU0_PE3_TX_C_DP<3>
  J6  = GND
  J7  = P5E_CPU0_PE3_TX_C_DP<1>
  J8  = GND
  K1  = GND
  K2  = P5E_CPU0_PE2_TX_C_DP<6>
  K3  = GND
  K4  = P5E_CPU0_PE2_TX_C_DP<4>
  K5  = GND
  K6  = P5E_CPU0_PE2_TX_C_DP<2>
  K7  = GND
  K8  = P5E_CPU0_PE2_TX_C_DP<0>
  L1  = P5E_CPU0_PE2_TX_C_DP<7>
  L2  = P5E_CPU0_PE2_TX_C_DN<6>
  L3  = P5E_CPU0_PE2_TX_C_DP<5>
  L4  = P5E_CPU0_PE2_TX_C_DN<4>
  L5  = P5E_CPU0_PE2_TX_C_DP<3>
  L6  = P5E_CPU0_PE2_TX_C_DN<2>
  L7  = P5E_CPU0_PE2_TX_C_DP<1>
  L8  = P5E_CPU0_PE2_TX_C_DN<0>
  M1  = P5E_CPU0_PE2_TX_C_DN<7>
  M2  = GND
  M3  = P5E_CPU0_PE2_TX_C_DN<5>
  M4  = GND
  M5  = P5E_CPU0_PE2_TX_C_DN<3>
  M6  = GND
  M7  = P5E_CPU0_PE2_TX_C_DN<1>
  M8  = GND
  N1  = GND
  N2  = FM_SWB_PWR_EN_R_BUF
  N3  = GND
  N4  = FM_SWB_BIC_READY_N
  N5  = GND
  N6  = RST_SWB_BIC_BUF_N
  N7  = GND
  N8  = RST_BMC_FROM_SWB_N

(kicad_pcb
	(version 20260206)
	(generator "pcbnew")
	(generator_version "10.0")
	(general
		(thickness 1.6)
		(legacy_teardrops no)
	)
	(paper "A4")
	(title_block
		(title "03242023_DA0F0TMBIJ0_F0T_Motherboard_J_brd_V01_OCP.brd")
		(comment 1 "Grand Teton / footprint 1792 of 6105 (J105), pads 1-31 of 48")
	)
	(layers
		(0 "F.Cu" signal "TOP")
		(4 "In1.Cu" signal "GND")
		(6 "In2.Cu" signal "IN1")
		(8 "In3.Cu" signal "GND1")
		(10 "In4.Cu" signal "IN2")
		(12 "In5.Cu" signal "GND2")
		(14 "In6.Cu" signal "IN3")
		(16 "In7.Cu" signal "GND3")
		(18 "In8.Cu" signal "VCC")
		(20 "In9.Cu" signal "VCC1")
		(22 "In10.Cu" signal "GND4")
		(24 "In11.Cu" signal "IN4")
		(26 "In12.Cu" signal "GND5")
		(28 "In13.Cu" signal "IN5")
		(30 "In14.Cu" signal "GND6")
		(32 "In15.Cu" signal "IN6")
		(34 "In16.Cu" signal "GND7")
		(2 "B.Cu" signal "BOTTOM")
		(9 "F.Adhes" user "F.Adhesive")
		(11 "B.Adhes" user "B.Adhesive")
		(13 "F.Paste" user "Package Geometry/Pastemask Top")
		(15 "B.Paste" user "Package Geometry/Pastemask Bottom")
		(5 "F.SilkS" user "Ref Des/Silkscreen Top")
		(7 "B.SilkS" user "Ref Des/Silkscreen Bottom")
		(1 "F.Mask" user "Board Geometry/Soldermask Top")
		(3 "B.Mask" user "Board Geometry/Soldermask Bottom")
		(17 "Dwgs.User" user "User.Drawings")
		(19 "Cmts.User" user "User.Comments")
		(21 "Eco1.User" user "User.Eco1")
		(23 "Eco2.User" user "User.Eco2")
		(25 "Edge.Cuts" user "Board Geometry/Outline")
		(27 "Margin" user)
		(31 "F.CrtYd" user "Package Geometry/Place Bound Top")
		(29 "B.CrtYd" user "Package Geometry/Place Bound Bottom")
		(35 "F.Fab" user "Ref Des/Assembly Top")
		(33 "B.Fab" user "Ref Des/Assembly Bottom")
	)
	(footprint ""
		(layer "F.Cu")
		(at 398.750028 -440.489848)
		(property "Reference" "J105"
			(at -2.99466 23.400512 0)
			(unlocked yes)
			(layer "F.SilkS")
			(effects
				(font
					(size 0.7874 0.5842)
					(thickness 0.1524)
				)
				(justify left)
			)
		)
		(property "Value" ""
			(at 0 0 0)
			(layer "F.Fab")
			(effects
				(font
					(size 1.27 1.27)
				)
			)
		)
		(duplicate_pad_numbers_are_jumpers no)
		(pad "A1" thru_hole rect
			(at 0 0 180)
			(size 0.766318 0.766318)
			(drill 0.359918)
			(layers "*.Cu" "*.Mask")
			(remove_unused_layers no)
			(net "GPU_3V3IO_RSVD4")
			(clearance 0.0508)
			(thermal_gap 0.0508)
			(padstack
				(mode front_inner_back)
				(layer "Inner"
					(shape circle)
					(size 0.766318 0.766318)
					(clearance 0.0508)
				)
				(layer "B.Cu"
					(shape rect)
					(size 0.766318 0.766318)
					(clearance 0.0508)
				)
			)
		)
		(pad "A2" thru_hole circle
			(at 1.999996 0.199898 180)
			(size 0.906272 0.906272)
			(drill 0.499872)
			(layers "*.Cu" "*.Mask")
			(remove_unused_layers no)
			(net "GND")
			(clearance 0.0508)
			(thermal_gap 0.0508)
		)
		(pad "A3" thru_hole circle
			(at 3.999992 0 180)
			(size 0.766318 0.766318)
			(drill 0.359918)
			(layers "*.Cu" "*.Mask")
			(remove_unused_layers no)
			(net "GPU_WP_HW_CTRL_ISO")
			(clearance 0.0508)
			(thermal_gap 0.0508)
		)
		(pad "A4" thru_hole circle
			(at 5.999988 0.199898 180)
			(size 0.906272 0.906272)
			(drill 0.499872)
			(layers "*.Cu" "*.Mask")
			(remove_unused_layers no)
			(net "GND")
			(clearance 0.0508)
			(thermal_gap 0.0508)
		)
		(pad "A5" thru_hole circle
			(at 7.999984 0 180)
			(size 0.766318 0.766318)
			(drill 0.359918)
			(layers "*.Cu" "*.Mask")
			(remove_unused_layers no)
			(net "GPU_3V3IO_RSVD3")
			(clearance 0.0508)
			(thermal_gap 0.0508)
		)
		(pad "A6" thru_hole circle
			(at 9.99998 0.199898 180)
			(size 0.906272 0.906272)
			(drill 0.499872)
			(layers "*.Cu" "*.Mask")
			(remove_unused_layers no)
			(net "GND")
			(clearance 0.0508)
			(thermal_gap 0.0508)
		)
		(pad "A7" thru_hole circle
			(at 11.999976 0 180)
			(size 0.766318 0.766318)
			(drill 0.359918)
			(layers "*.Cu" "*.Mask")
			(remove_unused_layers no)
			(net "GPU_3V3IO_RSVD1")
			(clearance 0.0508)
			(thermal_gap 0.0508)
		)
		(pad "A8" thru_hole circle
			(at 13.999972 0.199898 180)
			(size 0.906272 0.906272)
			(drill 0.499872)
			(layers "*.Cu" "*.Mask")
			(remove_unused_layers no)
			(net "GND")
			(clearance 0.0508)
			(thermal_gap 0.0508)
		)
		(pad "B1" thru_hole circle
			(at 0 1.199896 180)
			(size 0.906272 0.906272)
			(drill 0.499872)
			(layers "*.Cu" "*.Mask")
			(remove_unused_layers no)
			(net "GND")
			(clearance 0.0508)
			(thermal_gap 0.0508)
		)
		(pad "B3" thru_hole circle
			(at 3.999992 1.199896 180)
			(size 0.906272 0.906272)
			(drill 0.499872)
			(layers "*.Cu" "*.Mask")
			(remove_unused_layers no)
			(net "GND")
			(clearance 0.0508)
			(thermal_gap 0.0508)
		)
		(pad "B5" thru_hole circle
			(at 7.999984 1.199896 180)
			(size 0.906272 0.906272)
			(drill 0.499872)
			(layers "*.Cu" "*.Mask")
			(remove_unused_layers no)
			(net "GND")
			(clearance 0.0508)
			(thermal_gap 0.0508)
		)
		(pad "B7" thru_hole circle
			(at 11.999976 1.199896 180)
			(size 0.906272 0.906272)
			(drill 0.499872)
			(layers "*.Cu" "*.Mask")
			(remove_unused_layers no)
			(net "GND")
			(clearance 0.0508)
			(thermal_gap 0.0508)
		)
		(pad "D2" thru_hole circle
			(at 1.999996 3.800094 180)
			(size 0.906272 0.906272)
			(drill 0.499872)
			(layers "*.Cu" "*.Mask")
			(remove_unused_layers no)
			(net "GND")
			(clearance 0.0508)
			(thermal_gap 0.0508)
		)
		(pad "D4" thru_hole circle
			(at 5.999988 3.800094 180)
			(size 0.906272 0.906272)
			(drill 0.499872)
			(layers "*.Cu" "*.Mask")
			(remove_unused_layers no)
			(net "GND")
			(clearance 0.0508)
			(thermal_gap 0.0508)
		)
		(pad "D6" thru_hole circle
			(at 9.99998 3.800094 180)
			(size 0.906272 0.906272)
			(drill 0.499872)
			(layers "*.Cu" "*.Mask")
			(remove_unused_layers no)
			(net "GND")
			(clearance 0.0508)
			(thermal_gap 0.0508)
		)
		(pad "D8" thru_hole circle
			(at 13.999972 3.800094 180)
			(size 0.906272 0.906272)
			(drill 0.499872)
			(layers "*.Cu" "*.Mask")
			(remove_unused_layers no)
			(net "GND")
			(clearance 0.0508)
			(thermal_gap 0.0508)
		)
		(pad "E1" thru_hole circle
			(at 0 4.800092 180)
			(size 0.906272 0.906272)
			(drill 0.499872)
			(layers "*.Cu" "*.Mask")
			(remove_unused_layers no)
			(net "GND")
			(clearance 0.0508)
			(thermal_gap 0.0508)
		)
		(pad "E3" thru_hole circle
			(at 3.999992 4.800092 180)
			(size 0.906272 0.906272)
			(drill 0.499872)
			(layers "*.Cu" "*.Mask")
			(remove_unused_layers no)
			(net "GND")
			(clearance 0.0508)
			(thermal_gap 0.0508)
		)
		(pad "E5" thru_hole circle
			(at 7.999984 4.800092 180)
			(size 0.906272 0.906272)
			(drill 0.499872)
			(layers "*.Cu" "*.Mask")
			(remove_unused_layers no)
			(net "GND")
			(clearance 0.0508)
			(thermal_gap 0.0508)
		)
		(pad "E7" thru_hole circle
			(at 11.999976 4.800092 180)
			(size 0.906272 0.906272)
			(drill 0.499872)
			(layers "*.Cu" "*.Mask")
			(remove_unused_layers no)
			(net "GND")
			(clearance 0.0508)
			(thermal_gap 0.0508)
		)
		(pad "G2" thru_hole circle
			(at 1.999996 7.400036 180)
			(size 0.906272 0.906272)
			(drill 0.499872)
			(layers "*.Cu" "*.Mask")
			(remove_unused_layers no)
			(net "GND")
			(clearance 0.0508)
			(thermal_gap 0.0508)
		)
		(pad "G4" thru_hole circle
			(at 5.999988 7.400036 180)
			(size 0.906272 0.906272)
			(drill 0.499872)
			(layers "*.Cu" "*.Mask")
			(remove_unused_layers no)
			(net "GND")
			(clearance 0.0508)
			(thermal_gap 0.0508)
		)
		(pad "G6" thru_hole circle
			(at 9.99998 7.400036 180)
			(size 0.906272 0.906272)
			(drill 0.499872)
			(layers "*.Cu" "*.Mask")
			(remove_unused_layers no)
			(net "GND")
			(clearance 0.0508)
			(thermal_gap 0.0508)
		)
		(pad "G8" thru_hole circle
			(at 13.999972 7.400036 180)
			(size 0.906272 0.906272)
			(drill 0.499872)
			(layers "*.Cu" "*.Mask")
			(remove_unused_layers no)
			(net "GND")
			(clearance 0.0508)
			(thermal_gap 0.0508)
		)
		(pad "H1" thru_hole circle
			(at 0 8.400034 180)
			(size 0.906272 0.906272)
			(drill 0.499872)
			(layers "*.Cu" "*.Mask")
			(remove_unused_layers no)
			(net "GND")
			(clearance 0.0508)
			(thermal_gap 0.0508)
		)
		(pad "H3" thru_hole circle
			(at 3.999992 8.400034 180)
			(size 0.906272 0.906272)
			(drill 0.499872)
			(layers "*.Cu" "*.Mask")
			(remove_unused_layers no)
			(net "GND")
			(clearance 0.0508)
			(thermal_gap 0.0508)
		)
		(pad "H5" thru_hole circle
			(at 7.999984 8.400034 180)
			(size 0.906272 0.906272)
			(drill 0.499872)
			(layers "*.Cu" "*.Mask")
			(remove_unused_layers no)
			(net "GND")
			(clearance 0.0508)
			(thermal_gap 0.0508)
		)
		(pad "H7" thru_hole circle
			(at 11.999976 8.400034 180)
			(size 0.906272 0.906272)
			(drill 0.499872)
			(layers "*.Cu" "*.Mask")
			(remove_unused_layers no)
			(net "GND")
			(clearance 0.0508)
			(thermal_gap 0.0508)
		)
		(pad "J2" thru_hole circle
			(at 1.999996 10.999978 180)
			(size 0.906272 0.906272)
			(drill 0.499872)
			(layers "*.Cu" "*.Mask")
			(remove_unused_layers no)
			(net "GND")
			(clearance 0.0508)
			(thermal_gap 0.0508)
		)
		(pad "J4" thru_hole circle
			(at 5.999988 10.999978 180)
			(size 0.906272 0.906272)
			(drill 0.499872)
			(layers "*.Cu" "*.Mask")
			(remove_unused_layers no)
			(net "GND")
			(clearance 0.0508)
			(thermal_gap 0.0508)
		)
		(pad "J6" thru_hole circle
			(at 9.99998 10.999978 180)
			(size 0.906272 0.906272)
			(drill 0.499872)
			(layers "*.Cu" "*.Mask")
			(remove_unused_layers no)
			(net "GND")
			(clearance 0.0508)
			(thermal_gap 0.0508)
		)
	)
)
